# TIMECARD (Time Appliance Project (Time Card)) — schematic netlist excerpt (pin names and nets, part order shuffled) for the footprints in the layout excerpt that follows; sources: Cadence DE-HDL packaged netlist, KiCad conversion of R4006-B0001-02_R01.brd

R61  RESISTOR  0OHM -  pkg SMC_0402R_H016  page 16 : \1\ = VDD_PCA9546A ; \2\ = XP2R5V_FPGA
R59  RESISTOR  33OHM 1%  pkg SMC_0402R_H016  page 16 : \1\ = UNNAMED_5_CONNHDR2X2MSSMT_I12_1 ; \2\ = R_PCA9546_I2C_SCL

(kicad_pcb
	(version 20260206)
	(generator "pcbnew")
	(generator_version "10.0")
	(general
		(thickness 1.6)
		(legacy_teardrops no)
	)
	(paper "A4")
	(title_block
		(title "timecard-production-celestica-r4006 — R4006-B0001-02_R01.brd")
		(comment 1 "Time Appliance Project (Time Card) / footprints 679-680 of 1113")
	)
	(layers
		(0 "F.Cu" signal "TOP")
		(4 "In1.Cu" signal "L02_GND1")
		(6 "In2.Cu" signal "L03_SIG1")
		(8 "In3.Cu" signal "L04_GND2")
		(10 "In4.Cu" signal "L05_VCC1")
		(12 "In5.Cu" signal "L06_VCC2")
		(14 "In6.Cu" signal "L07_GND3")
		(16 "In7.Cu" signal "L08_SIG2")
		(18 "In8.Cu" signal "L09_GND4")
		(2 "B.Cu" signal "BOTTOM")
		(9 "F.Adhes" user "F.Adhesive")
		(11 "B.Adhes" user "B.Adhesive")
		(13 "F.Paste" user "Package Geometry/Pastemask Top")
		(15 "B.Paste" user "Package Geometry/Pastemask Bottom")
		(5 "F.SilkS" user "Ref Des/Silkscreen Top")
		(7 "B.SilkS" user "Ref Des/Silkscreen Bottom")
		(1 "F.Mask" user "Board Geometry/Soldermask Top")
		(3 "B.Mask" user "Board Geometry/Soldermask Bottom")
		(17 "Dwgs.User" user "User.Drawings")
		(19 "Cmts.User" user "User.Comments")
		(21 "Eco1.User" user "User.Eco1")
		(23 "Eco2.User" user "User.Eco2")
		(25 "Edge.Cuts" user "Board Geometry/Outline")
		(27 "Margin" user)
		(31 "F.CrtYd" user "Package Geometry/Place Bound Top")
		(29 "B.CrtYd" user "Package Geometry/Place Bound Bottom")
		(35 "F.Fab" user "Ref Des/Assembly Top")
		(33 "B.Fab" user "Ref Des/Assembly Bottom")
	)
	(footprint ""
		(layer "B.Cu")
		(at 17.653 -37.973 180)
		(property "Reference" "R59"
			(at 0 -2.32537 0)
			(unlocked yes)
			(layer "B.SilkS")
			(effects
				(font
					(size 0.7874 0.5842)
					(thickness 0.1524)
				)
				(justify mirror)
			)
		)
		(property "Value" "VAL*"
			(at -0.02032 2.13233 180)
			(unlocked yes)
			(layer "B.Fab")
			(hide yes)
			(effects
				(font
					(size 0.7874 0.5842)
					(thickness 0.1524)
				)
				(justify mirror)
			)
		)
		(property "Device Type" "RESISTOR-G155-133R0-01,33OHM,1%"
			(at -0.008382 1.210564 180)
			(unlocked yes)
			(layer "B.Fab")
			(hide yes)
			(effects
				(font
					(size 0.7874 0.5842)
					(thickness 0.1524)
				)
				(justify mirror)
			)
		)
		(property "User Part Number" "PARTNUM*"
			(at -0.02032 4.024884 180)
			(unlocked yes)
			(layer "Cmts.User")
			(hide yes)
			(effects
				(font
					(size 0.7874 0.5842)
					(thickness 0.1524)
				)
				(justify mirror)
			)
		)
		(property "Tolerance" "TOL*"
			(at -0.044704 3.05435 180)
			(unlocked yes)
			(layer "Cmts.User")
			(hide yes)
			(effects
				(font
					(size 0.7874 0.5842)
					(thickness 0.1524)
				)
				(justify mirror)
			)
		)
		(duplicate_pad_numbers_are_jumpers no)
		(fp_line
			(start 1.143 0.5588)
			(end -1.143 0.5588)
			(stroke
				(width 0.1)
				(type default)
			)
			(layer "B.SilkS")
		)
		(fp_line
			(start 1.143 -0.5588)
			(end 1.143 0.5588)
			(stroke
				(width 0.1)
				(type default)
			)
			(layer "B.SilkS")
		)
		(fp_line
			(start -1.143 0.5588)
			(end -1.143 -0.5588)
			(stroke
				(width 0.1)
				(type default)
			)
			(layer "B.SilkS")
		)
		(fp_line
			(start -1.143 -0.5588)
			(end 1.143 -0.5588)
			(stroke
				(width 0.1)
				(type default)
			)
			(layer "B.SilkS")
		)
		(fp_rect
			(start 1.143 0.5588)
			(end -1.143 -0.5588)
			(stroke
				(width 0)
				(type default)
			)
			(fill no)
			(layer "B.CrtYd")
		)
		(fp_line
			(start 0.508 0.3048)
			(end -0.508 0.3048)
			(stroke
				(width 0.1)
				(type default)
			)
			(layer "B.Fab")
		)
		(fp_line
			(start 0.508 -0.3048)
			(end 0.508 0.3048)
			(stroke
				(width 0.1)
				(type default)
			)
			(layer "B.Fab")
		)
		(fp_line
			(start -0.508 0.3048)
			(end -0.508 -0.3048)
			(stroke
				(width 0.1)
				(type default)
			)
			(layer "B.Fab")
		)
		(fp_line
			(start -0.508 -0.3048)
			(end 0.508 -0.3048)
			(stroke
				(width 0.1)
				(type default)
			)
			(layer "B.Fab")
		)
		(pad "1" smd rect
			(at 0.5334 0)
			(size 0.7112 0.6096)
			(layers "B.Cu" "B.Mask" "B.Paste")
			(net "UNNAMED_5_CONNHDR2X2MSSMT_I12_1")
		)
		(pad "2" smd rect
			(at -0.5334 0)
			(size 0.7112 0.6096)
			(layers "B.Cu" "B.Mask" "B.Paste")
			(net "R_PCA9546_I2C_SCL")
		)
		(zone
			(layer "B.Cu")
			(hatch none 0.5)
			(connect_pads
				(clearance 0)
			)
			(min_thickness 0.25)
			(keepout
				(tracks allowed)
				(vias not_allowed)
				(pads allowed)
				(copperpour not_allowed)
				(footprints allowed)
			)
			(placement
				(enabled no)
				(sheetname "")
			)
			(fill
				(thermal_gap 0.5)
				(thermal_bridge_width 0.5)
				(island_removal_mode 0)
			)
			(polygon
				(pts
					(xy 17.5768 -38.2778) (xy 17.5768 -37.6682) (xy 17.7292 -37.6682) (xy 17.7292 -38.2778)
				)
			)
		)
	)
	(footprint ""
		(layer "B.Cu")
		(at 77.3938 -81.534 180)
		(property "Reference" "R61"
			(at 2.9718 -0.03937 0)
			(unlocked yes)
			(layer "B.SilkS")
			(effects
				(font
					(size 0.7874 0.5842)
					(thickness 0.1524)
				)
				(justify mirror)
			)
		)
		(property "Value" "VAL*"
			(at -0.02032 2.13233 180)
			(unlocked yes)
			(layer "B.Fab")
			(hide yes)
			(effects
				(font
					(size 0.7874 0.5842)
					(thickness 0.1524)
				)
				(justify mirror)
			)
		)
		(property "Tolerance" "TOL*"
			(at -0.044704 3.05435 180)
			(unlocked yes)
			(layer "Cmts.User")
			(hide yes)
			(effects
				(font
					(size 0.7874 0.5842)
					(thickness 0.1524)
				)
				(justify mirror)
			)
		)
		(property "User Part Number" "PARTNUM*"
			(at -0.02032 4.024884 180)
			(unlocked yes)
			(layer "Cmts.User")
			(hide yes)
			(effects
				(font
					(size 0.7874 0.5842)
					(thickness 0.1524)
				)
				(justify mirror)
			)
		)
		(property "Device Type" "RESISTOR-G155-100R0-J0,0OHM,-"
			(at -0.008382 1.210564 180)
			(unlocked yes)
			(layer "B.Fab")
			(hide yes)
			(effects
				(font
					(size 0.7874 0.5842)
					(thickness 0.1524)
				)
				(justify mirror)
			)
		)
		(duplicate_pad_numbers_are_jumpers no)
		(fp_line
			(start 1.143 0.5588)
			(end -1.143 0.5588)
			(stroke
				(width 0.1)
				(type default)
			)
			(layer "B.SilkS")
		)
		(fp_line
			(start 1.143 -0.5588)
			(end 1.143 0.5588)
			(stroke
				(width 0.1)
				(type default)
			)
			(layer "B.SilkS")
		)
		(fp_line
			(start -1.143 0.5588)
			(end -1.143 -0.5588)
			(stroke
				(width 0.1)
				(type default)
			)
			(layer "B.SilkS")
		)
		(fp_line
			(start -1.143 -0.5588)
			(end 1.143 -0.5588)
			(stroke
				(width 0.1)
				(type default)
			)
			(layer "B.SilkS")
		)
		(fp_poly
			(pts
				(xy 1.143 0.5588) (xy -1.143 0.5588) (xy -1.143 -0.5588) (xy 1.143 -0.5588)
			)
			(stroke
				(width 0)
				(type default)
			)
			(fill no)
			(layer "B.CrtYd")
		)
		(fp_line
			(start 0.508 0.3048)
			(end -0.508 0.3048)
			(stroke
				(width 0.1)
				(type default)
			)
			(layer "B.Fab")
		)
		(fp_line
			(start 0.508 -0.3048)
			(end 0.508 0.3048)
			(stroke
				(width 0.1)
				(type default)
			)
			(layer "B.Fab")
		)
		(fp_line
			(start -0.508 0.3048)
			(end -0.508 -0.3048)
			(stroke
				(width 0.1)
				(type default)
			)
			(layer "B.Fab")
		)
		(fp_line
			(start -0.508 -0.3048)
			(end 0.508 -0.3048)
			(stroke
				(width 0.1)
				(type default)
			)
			(layer "B.Fab")
		)
		(pad "1" smd rect
			(at 0.5334 0)
			(size 0.7112 0.6096)
			(layers "B.Cu" "B.Mask" "B.Paste")
			(net "VDD_PCA9546A")
		)
		(pad "2" smd rect
			(at -0.5334 0)
			(size 0.7112 0.6096)
			(layers "B.Cu" "B.Mask" "B.Paste")
			(net "XP2R5V_FPGA")
		)
		(zone
			(layer "B.Cu")
			(hatch none 0.5)
			(connect_pads
				(clearance 0)
			)
			(min_thickness 0.25)
			(keepout
				(tracks not_allowed)
				(vias allowed)
				(pads allowed)
				(copperpour not_allowed)
				(footprints allowed)
			)
			(placement
				(enabled no)
				(sheetname "")
			)
			(fill
				(thermal_gap 0.5)
				(thermal_bridge_width 0.5)
				(island_removal_mode 0)
			)
			(polygon
				(pts
					(xy 77.3176 -81.8388) (xy 77.3176 -81.2292) (xy 77.47 -81.2292) (xy 77.47 -81.8388)
				)
			)
		)
		(zone
			(layer "B.Cu")
			(hatch none 0.5)
			(connect_pads
				(clearance 0)
			)
			(min_thickness 0.25)
			(keepout
				(tracks allowed)
				(vias not_allowed)
				(pads allowed)
				(copperpour not_allowed)
				(footprints allowed)
			)
			(placement
				(enabled no)
				(sheetname "")
			)
			(fill
				(thermal_gap 0.5)
				(thermal_bridge_width 0.5)
				(island_removal_mode 0)
			)
			(polygon
				(pts
					(xy 77.3176 -81.8388) (xy 77.3176 -81.2292) (xy 77.47 -81.2292) (xy 77.47 -81.8388)
				)
			)
		)
	)
)
